(kicad_pcb
	(version 20260206)
	(generator "pcbnew")
	(generator_version "10.0")
	(general
		(thickness 1.6)
		(legacy_teardrops no)
	)
	(paper "A4")
	(title_block
		(title "01162023_DA0F0TEBIF0_F0T_Expander_BD_F_brd_V02_OCP.brd")
		(comment 1 "Grand Teton / footprints 6978-6985 of 9728")
	)
	(layers
		(0 "F.Cu" signal "TOP")
		(4 "In1.Cu" signal "GND")
		(6 "In2.Cu" signal "VCC")
		(8 "In3.Cu" signal "VCC1")
		(10 "In4.Cu" signal "GND1")
		(12 "In5.Cu" signal "IN1")
		(14 "In6.Cu" signal "GND2")
		(16 "In7.Cu" signal "IN2")
		(18 "In8.Cu" signal "GND3")
		(20 "In9.Cu" signal "IN3")
		(22 "In10.Cu" signal "GND4")
		(24 "In11.Cu" signal "IN4")
		(26 "In12.Cu" signal "GND5")
		(28 "In13.Cu" signal "IN5")
		(30 "In14.Cu" signal "GND6")
		(32 "In15.Cu" signal "IN6")
		(34 "In16.Cu" signal "GND7")
		(2 "B.Cu" signal "BOTTOM")
		(9 "F.Adhes" user "F.Adhesive")
		(11 "B.Adhes" user "B.Adhesive")
		(13 "F.Paste" user "Package Geometry/Pastemask Top")
		(15 "B.Paste" user "Package Geometry/Pastemask Bottom")
		(5 "F.SilkS" user "Ref Des/Silkscreen Top")
		(7 "B.SilkS" user "Ref Des/Silkscreen Bottom")
		(1 "F.Mask" user "Board Geometry/Soldermask Top")
		(3 "B.Mask" user "Board Geometry/Soldermask Bottom")
		(17 "Dwgs.User" user "User.Drawings")
		(19 "Cmts.User" user "User.Comments")
		(21 "Eco1.User" user "User.Eco1")
		(23 "Eco2.User" user "User.Eco2")
		(25 "Edge.Cuts" user "Board Geometry/Outline")
		(27 "Margin" user)
		(31 "F.CrtYd" user "Package Geometry/Place Bound Top")
		(29 "B.CrtYd" user "Package Geometry/Place Bound Bottom")
		(35 "F.Fab" user "Ref Des/Assembly Top")
		(33 "B.Fab" user "Ref Des/Assembly Bottom")
	)
	(footprint ""
		(layer "F.Cu")
		(at 238.28375 -59.751976 -90)
		(property "Reference" "PR7079"
			(at 0 0 270)
			(layer "F.SilkS")
			(hide yes)
			(effects
				(font
					(size 1.27 1.27)
				)
			)
		)
		(property "Value" ""
			(at 0 0 270)
			(layer "F.Fab")
			(effects
				(font
					(size 1.27 1.27)
				)
			)
		)
		(duplicate_pad_numbers_are_jumpers no)
		(fp_line
			(start -0.7874 0.4064)
			(end -0.7874 -0.4064)
			(stroke
				(width 0.1524)
				(type default)
			)
			(layer "F.SilkS")
		)
		(fp_line
			(start 0.7874 0.4064)
			(end -0.7874 0.4064)
			(stroke
				(width 0.1524)
				(type default)
			)
			(layer "F.SilkS")
		)
		(fp_line
			(start -0.7874 -0.4064)
			(end 0.7874 -0.4064)
			(stroke
				(width 0.1524)
				(type default)
			)
			(layer "F.SilkS")
		)
		(fp_line
			(start 0.7874 -0.4064)
			(end 0.7874 0.4064)
			(stroke
				(width 0.1524)
				(type default)
			)
			(layer "F.SilkS")
		)
		(fp_line
			(start -0.67945 0.3048)
			(end -0.67945 -0.305054)
			(stroke
				(width 0.1)
				(type default)
			)
			(layer "F.Fab")
		)
		(fp_line
			(start -0.12065 0.3048)
			(end -0.67945 0.3048)
			(stroke
				(width 0.1)
				(type default)
			)
			(layer "F.Fab")
		)
		(fp_line
			(start 0.120396 0.3048)
			(end 0.120396 0.2794)
			(stroke
				(width 0.1)
				(type default)
			)
			(layer "F.Fab")
		)
		(fp_line
			(start 0.67945 0.3048)
			(end 0.120396 0.3048)
			(stroke
				(width 0.1)
				(type default)
			)
			(layer "F.Fab")
		)
		(fp_line
			(start -0.12065 0.2794)
			(end -0.12065 0.3048)
			(stroke
				(width 0.1)
				(type default)
			)
			(layer "F.Fab")
		)
		(fp_line
			(start 0.120396 0.2794)
			(end -0.12065 0.2794)
			(stroke
				(width 0.1)
				(type default)
			)
			(layer "F.Fab")
		)
		(fp_line
			(start -0.12065 -0.2794)
			(end 0.12065 -0.2794)
			(stroke
				(width 0.1)
				(type default)
			)
			(layer "F.Fab")
		)
		(fp_line
			(start 0.12065 -0.2794)
			(end 0.12065 -0.3048)
			(stroke
				(width 0.1)
				(type default)
			)
			(layer "F.Fab")
		)
		(fp_line
			(start 0.12065 -0.3048)
			(end 0.67945 -0.3048)
			(stroke
				(width 0.1)
				(type default)
			)
			(layer "F.Fab")
		)
		(fp_line
			(start 0.67945 -0.3048)
			(end 0.67945 0.3048)
			(stroke
				(width 0.1)
				(type default)
			)
			(layer "F.Fab")
		)
		(fp_line
			(start -0.67945 -0.305054)
			(end -0.12065 -0.305054)
			(stroke
				(width 0.1)
				(type default)
			)
			(layer "F.Fab")
		)
		(fp_line
			(start -0.12065 -0.305054)
			(end -0.12065 -0.2794)
			(stroke
				(width 0.1)
				(type default)
			)
			(layer "F.Fab")
		)
		(pad "1" smd circle
			(at -0.40005 0 270)
			(size 0 0)
			(layers "F.Cu" "F.Mask" "F.Paste")
			(net "P12V_SSD8_PG_G1")
		)
		(pad "2" smd circle
			(at 0.40005 0 270)
			(size 0 0)
			(layers "F.Cu" "F.Mask" "F.Paste")
			(net "GND")
		)
	)
	(footprint ""
		(layer "F.Cu")
		(at 265.311382 -258.234434)
		(property "Reference" "L125"
			(at 0 0 0)
			(layer "F.SilkS")
			(hide yes)
			(effects
				(font
					(size 1.27 1.27)
				)
			)
		)
		(property "Value" ""
			(at 0 0 0)
			(layer "F.Fab")
			(effects
				(font
					(size 1.27 1.27)
				)
			)
		)
		(duplicate_pad_numbers_are_jumpers no)
		(fp_line
			(start -1.63576 -0.8128)
			(end -1.63576 0.8128)
			(stroke
				(width 0.1524)
				(type default)
			)
			(layer "F.SilkS")
		)
		(fp_line
			(start -1.63576 -0.8128)
			(end 1.63576 -0.8128)
			(stroke
				(width 0.1524)
				(type default)
			)
			(layer "F.SilkS")
		)
		(fp_line
			(start 1.63576 -0.8128)
			(end 1.63576 0.8128)
			(stroke
				(width 0.1524)
				(type default)
			)
			(layer "F.SilkS")
		)
		(fp_line
			(start 1.63576 0.8128)
			(end -1.63576 0.8128)
			(stroke
				(width 0.1524)
				(type default)
			)
			(layer "F.SilkS")
		)
		(fp_line
			(start -1.56083 -0.738632)
			(end -1.56083 0.7366)
			(stroke
				(width 0.1)
				(type default)
			)
			(layer "F.Fab")
		)
		(fp_line
			(start -1.56083 0.7366)
			(end -1.524 0.7366)
			(stroke
				(width 0.1)
				(type default)
			)
			(layer "F.Fab")
		)
		(fp_line
			(start -1.524 0.7366)
			(end 1.524 0.7366)
			(stroke
				(width 0.1)
				(type default)
			)
			(layer "F.Fab")
		)
		(fp_line
			(start 1.524 0.7366)
			(end 1.560576 0.7366)
			(stroke
				(width 0.1)
				(type default)
			)
			(layer "F.Fab")
		)
		(fp_line
			(start 1.560576 -0.738632)
			(end -1.56083 -0.738632)
			(stroke
				(width 0.1)
				(type default)
			)
			(layer "F.Fab")
		)
		(fp_line
			(start 1.560576 0.7366)
			(end 1.560576 -0.738632)
			(stroke
				(width 0.1)
				(type default)
			)
			(layer "F.Fab")
		)
		(pad "1" smd rect
			(at -0.94996 0 180)
			(size 1.1176 1.3716)
			(layers "F.Cu" "F.Mask" "F.Paste")
			(net "P1V8_PLL0_PEX2")
		)
		(pad "2" smd rect
			(at 0.94996 0 180)
			(size 1.1176 1.3716)
			(layers "F.Cu" "F.Mask" "F.Paste")
			(net "PCEPLL5_VDDA18_PEX2")
		)
	)
	(footprint ""
		(layer "F.Cu")
		(at 394.734542 -30.03169 180)
		(property "Reference" "C711"
			(at 0 0 180)
			(layer "F.SilkS")
			(hide yes)
			(effects
				(font
					(size 1.27 1.27)
				)
			)
		)
		(property "Value" ""
			(at 0 0 180)
			(layer "F.Fab")
			(effects
				(font
					(size 1.27 1.27)
				)
			)
		)
		(duplicate_pad_numbers_are_jumpers no)
		(fp_line
			(start 0.299974 0.150114)
			(end -0.299974 0.150114)
			(stroke
				(width 0.1)
				(type default)
			)
			(layer "F.Fab")
		)
		(fp_line
			(start 0.299974 -0.150114)
			(end 0.299974 0.150114)
			(stroke
				(width 0.1)
				(type default)
			)
			(layer "F.Fab")
		)
		(fp_line
			(start -0.299974 0.150114)
			(end -0.299974 -0.150114)
			(stroke
				(width 0.1)
				(type default)
			)
			(layer "F.Fab")
		)
		(fp_line
			(start -0.299974 -0.150114)
			(end 0.299974 -0.150114)
			(stroke
				(width 0.1)
				(type default)
			)
			(layer "F.Fab")
		)
		(pad "1" smd rect
			(at -0.2667 0 180)
			(size 0.3048 0.381)
			(layers "F.Cu" "F.Mask" "F.Paste")
			(net "P5E_PEX3_STN2_TX_DN<41>")
		)
		(pad "2" smd rect
			(at 0.2667 0 180)
			(size 0.3048 0.381)
			(layers "F.Cu" "F.Mask" "F.Paste")
			(net "P5E_PEX3_STN2_TX_C_DN<41>")
		)
	)
	(footprint ""
		(layer "F.Cu")
		(at 78.912974 -8.891778 180)
		(property "Reference" "C3870"
			(at 0 0 180)
			(layer "F.SilkS")
			(hide yes)
			(effects
				(font
					(size 1.27 1.27)
				)
			)
		)
		(property "Value" ""
			(at 0 0 180)
			(layer "F.Fab")
			(effects
				(font
					(size 1.27 1.27)
				)
			)
		)
		(duplicate_pad_numbers_are_jumpers no)
		(fp_line
			(start 0.7874 0.4064)
			(end -0.7874 0.4064)
			(stroke
				(width 0.1524)
				(type default)
			)
			(layer "F.SilkS")
		)
		(fp_line
			(start 0.7874 -0.4064)
			(end 0.7874 0.4064)
			(stroke
				(width 0.1524)
				(type default)
			)
			(layer "F.SilkS")
		)
		(fp_line
			(start -0.7874 0.4064)
			(end -0.7874 -0.4064)
			(stroke
				(width 0.1524)
				(type default)
			)
			(layer "F.SilkS")
		)
		(fp_line
			(start -0.7874 -0.4064)
			(end 0.7874 -0.4064)
			(stroke
				(width 0.1524)
				(type default)
			)
			(layer "F.SilkS")
		)
		(fp_line
			(start 0.67945 0.3048)
			(end 0.120396 0.3048)
			(stroke
				(width 0.1)
				(type default)
			)
			(layer "F.Fab")
		)
		(fp_line
			(start 0.67945 -0.3048)
			(end 0.67945 0.3048)
			(stroke
				(width 0.1)
				(type default)
			)
			(layer "F.Fab")
		)
		(fp_line
			(start 0.12065 -0.2794)
			(end 0.12065 -0.3048)
			(stroke
				(width 0.1)
				(type default)
			)
			(layer "F.Fab")
		)
		(fp_line
			(start 0.12065 -0.3048)
			(end 0.67945 -0.3048)
			(stroke
				(width 0.1)
				(type default)
			)
			(layer "F.Fab")
		)
		(fp_line
			(start 0.120396 0.3048)
			(end 0.120396 0.2794)
			(stroke
				(width 0.1)
				(type default)
			)
			(layer "F.Fab")
		)
		(fp_line
			(start 0.120396 0.2794)
			(end -0.12065 0.2794)
			(stroke
				(width 0.1)
				(type default)
			)
			(layer "F.Fab")
		)
		(fp_line
			(start -0.12065 0.3048)
			(end -0.67945 0.3048)
			(stroke
				(width 0.1)
				(type default)
			)
			(layer "F.Fab")
		)
		(fp_line
			(start -0.12065 0.2794)
			(end -0.12065 0.3048)
			(stroke
				(width 0.1)
				(type default)
			)
			(layer "F.Fab")
		)
		(fp_line
			(start -0.12065 -0.2794)
			(end 0.12065 -0.2794)
			(stroke
				(width 0.1)
				(type default)
			)
			(layer "F.Fab")
		)
		(fp_line
			(start -0.12065 -0.305054)
			(end -0.12065 -0.2794)
			(stroke
				(width 0.1)
				(type default)
			)
			(layer "F.Fab")
		)
		(fp_line
			(start -0.67945 0.3048)
			(end -0.67945 -0.305054)
			(stroke
				(width 0.1)
				(type default)
			)
			(layer "F.Fab")
		)
		(fp_line
			(start -0.67945 -0.305054)
			(end -0.12065 -0.305054)
			(stroke
				(width 0.1)
				(type default)
			)
			(layer "F.Fab")
		)
		(pad "1" smd circle
			(at -0.40005 0 180)
			(size 0 0)
			(layers "F.Cu" "F.Mask" "F.Paste")
			(net "P3V3_AUX")
		)
		(pad "2" smd circle
			(at 0.40005 0 180)
			(size 0 0)
			(layers "F.Cu" "F.Mask" "F.Paste")
			(net "GND")
		)
	)
	(footprint ""
		(layer "F.Cu")
		(at 62.96279 -382.538732 180)
		(property "Reference" "C4030"
			(at 0 0 180)
			(layer "F.SilkS")
			(hide yes)
			(effects
				(font
					(size 1.27 1.27)
				)
			)
		)
		(property "Value" ""
			(at 0 0 180)
			(layer "F.Fab")
			(effects
				(font
					(size 1.27 1.27)
				)
			)
		)
		(duplicate_pad_numbers_are_jumpers no)
		(fp_line
			(start 0.7874 0.4064)
			(end -0.7874 0.4064)
			(stroke
				(width 0.1524)
				(type default)
			)
			(layer "F.SilkS")
		)
		(fp_line
			(start 0.7874 -0.4064)
			(end 0.7874 0.4064)
			(stroke
				(width 0.1524)
				(type default)
			)
			(layer "F.SilkS")
		)
		(fp_line
			(start -0.7874 0.4064)
			(end -0.7874 -0.4064)
			(stroke
				(width 0.1524)
				(type default)
			)
			(layer "F.SilkS")
		)
		(fp_line
			(start -0.7874 -0.4064)
			(end 0.7874 -0.4064)
			(stroke
				(width 0.1524)
				(type default)
			)
			(layer "F.SilkS")
		)
		(fp_line
			(start 0.67945 0.3048)
			(end 0.120396 0.3048)
			(stroke
				(width 0.1)
				(type default)
			)
			(layer "F.Fab")
		)
		(fp_line
			(start 0.67945 -0.3048)
			(end 0.67945 0.3048)
			(stroke
				(width 0.1)
				(type default)
			)
			(layer "F.Fab")
		)
		(fp_line
			(start 0.12065 -0.2794)
			(end 0.12065 -0.3048)
			(stroke
				(width 0.1)
				(type default)
			)
			(layer "F.Fab")
		)
		(fp_line
			(start 0.12065 -0.3048)
			(end 0.67945 -0.3048)
			(stroke
				(width 0.1)
				(type default)
			)
			(layer "F.Fab")
		)
		(fp_line
			(start 0.120396 0.3048)
			(end 0.120396 0.2794)
			(stroke
				(width 0.1)
				(type default)
			)
			(layer "F.Fab")
		)
		(fp_line
			(start 0.120396 0.2794)
			(end -0.12065 0.2794)
			(stroke
				(width 0.1)
				(type default)
			)
			(layer "F.Fab")
		)
		(fp_line
			(start -0.12065 0.3048)
			(end -0.67945 0.3048)
			(stroke
				(width 0.1)
				(type default)
			)
			(layer "F.Fab")
		)
		(fp_line
			(start -0.12065 0.2794)
			(end -0.12065 0.3048)
			(stroke
				(width 0.1)
				(type default)
			)
			(layer "F.Fab")
		)
		(fp_line
			(start -0.12065 -0.2794)
			(end 0.12065 -0.2794)
			(stroke
				(width 0.1)
				(type default)
			)
			(layer "F.Fab")
		)
		(fp_line
			(start -0.12065 -0.305054)
			(end -0.12065 -0.2794)
			(stroke
				(width 0.1)
				(type default)
			)
			(layer "F.Fab")
		)
		(fp_line
			(start -0.67945 0.3048)
			(end -0.67945 -0.305054)
			(stroke
				(width 0.1)
				(type default)
			)
			(layer "F.Fab")
		)
		(fp_line
			(start -0.67945 -0.305054)
			(end -0.12065 -0.305054)
			(stroke
				(width 0.1)
				(type default)
			)
			(layer "F.Fab")
		)
		(pad "1" smd circle
			(at -0.40005 0 180)
			(size 0 0)
			(layers "F.Cu" "F.Mask" "F.Paste")
			(net "GND")
		)
		(pad "2" smd circle
			(at 0.40005 0 180)
			(size 0 0)
			(layers "F.Cu" "F.Mask" "F.Paste")
			(net "RST_MB_PERST_2_N")
		)
	)
	(footprint ""
		(layer "F.Cu")
		(at 82.90179 -32.849312 90)
		(property "Reference" "R5658"
			(at 0 0 90)
			(layer "F.SilkS")
			(hide yes)
			(effects
				(font
					(size 1.27 1.27)
				)
			)
		)
		(property "Value" ""
			(at 0 0 90)
			(layer "F.Fab")
			(effects
				(font
					(size 1.27 1.27)
				)
			)
		)
		(duplicate_pad_numbers_are_jumpers no)
		(fp_line
			(start 0.7874 -0.4064)
			(end 0.7874 0.4064)
			(stroke
				(width 0.1524)
				(type default)
			)
			(layer "F.SilkS")
		)
		(fp_line
			(start -0.7874 -0.4064)
			(end 0.7874 -0.4064)
			(stroke
				(width 0.1524)
				(type default)
			)
			(layer "F.SilkS")
		)
		(fp_line
			(start 0.7874 0.4064)
			(end -0.7874 0.4064)
			(stroke
				(width 0.1524)
				(type default)
			)
			(layer "F.SilkS")
		)
		(fp_line
			(start -0.7874 0.4064)
			(end -0.7874 -0.4064)
			(stroke
				(width 0.1524)
				(type default)
			)
			(layer "F.SilkS")
		)
		(fp_line
			(start -0.12065 -0.305054)
			(end -0.12065 -0.2794)
			(stroke
				(width 0.1)
				(type default)
			)
			(layer "F.Fab")
		)
		(fp_line
			(start -0.67945 -0.305054)
			(end -0.12065 -0.305054)
			(stroke
				(width 0.1)
				(type default)
			)
			(layer "F.Fab")
		)
		(fp_line
			(start 0.67945 -0.3048)
			(end 0.67945 0.3048)
			(stroke
				(width 0.1)
				(type default)
			)
			(layer "F.Fab")
		)
		(fp_line
			(start 0.12065 -0.3048)
			(end 0.67945 -0.3048)
			(stroke
				(width 0.1)
				(type default)
			)
			(layer "F.Fab")
		)
		(fp_line
			(start 0.12065 -0.2794)
			(end 0.12065 -0.3048)
			(stroke
				(width 0.1)
				(type default)
			)
			(layer "F.Fab")
		)
		(fp_line
			(start -0.12065 -0.2794)
			(end 0.12065 -0.2794)
			(stroke
				(width 0.1)
				(type default)
			)
			(layer "F.Fab")
		)
		(fp_line
			(start 0.120396 0.2794)
			(end -0.12065 0.2794)
			(stroke
				(width 0.1)
				(type default)
			)
			(layer "F.Fab")
		)
		(fp_line
			(start -0.12065 0.2794)
			(end -0.12065 0.3048)
			(stroke
				(width 0.1)
				(type default)
			)
			(layer "F.Fab")
		)
		(fp_line
			(start 0.67945 0.3048)
			(end 0.120396 0.3048)
			(stroke
				(width 0.1)
				(type default)
			)
			(layer "F.Fab")
		)
		(fp_line
			(start 0.120396 0.3048)
			(end 0.120396 0.2794)
			(stroke
				(width 0.1)
				(type default)
			)
			(layer "F.Fab")
		)
		(fp_line
			(start -0.12065 0.3048)
			(end -0.67945 0.3048)
			(stroke
				(width 0.1)
				(type default)
			)
			(layer "F.Fab")
		)
		(fp_line
			(start -0.67945 0.3048)
			(end -0.67945 -0.305054)
			(stroke
				(width 0.1)
				(type default)
			)
			(layer "F.Fab")
		)
		(pad "1" smd circle
			(at -0.40005 0 90)
			(size 0 0)
			(layers "F.Cu" "F.Mask" "F.Paste")
			(net "RST_SMB_SSD3_ISO_R_N")
		)
		(pad "2" smd circle
			(at 0.40005 0 90)
			(size 0 0)
			(layers "F.Cu" "F.Mask" "F.Paste")
			(net "RST_SMB_SSD3_ISO_N")
		)
	)
	(footprint ""
		(layer "F.Cu")
		(at 194.367912 -54.067456)
		(property "Reference" "PR218"
			(at 0 0 0)
			(layer "F.SilkS")
			(hide yes)
			(effects
				(font
					(size 1.27 1.27)
				)
			)
		)
		(property "Value" ""
			(at 0 0 0)
			(layer "F.Fab")
			(effects
				(font
					(size 1.27 1.27)
				)
			)
		)
		(duplicate_pad_numbers_are_jumpers no)
		(fp_line
			(start -0.7874 -0.4064)
			(end 0.7874 -0.4064)
			(stroke
				(width 0.1524)
				(type default)
			)
			(layer "F.SilkS")
		)
		(fp_line
			(start -0.7874 0.4064)
			(end -0.7874 -0.4064)
			(stroke
				(width 0.1524)
				(type default)
			)
			(layer "F.SilkS")
		)
		(fp_line
			(start 0.7874 -0.4064)
			(end 0.7874 0.4064)
			(stroke
				(width 0.1524)
				(type default)
			)
			(layer "F.SilkS")
		)
		(fp_line
			(start 0.7874 0.4064)
			(end -0.7874 0.4064)
			(stroke
				(width 0.1524)
				(type default)
			)
			(layer "F.SilkS")
		)
		(fp_line
			(start -0.67945 -0.305054)
			(end -0.12065 -0.305054)
			(stroke
				(width 0.1)
				(type default)
			)
			(layer "F.Fab")
		)
		(fp_line
			(start -0.67945 0.3048)
			(end -0.67945 -0.305054)
			(stroke
				(width 0.1)
				(type default)
			)
			(layer "F.Fab")
		)
		(fp_line
			(start -0.12065 -0.305054)
			(end -0.12065 -0.2794)
			(stroke
				(width 0.1)
				(type default)
			)
			(layer "F.Fab")
		)
		(fp_line
			(start -0.12065 -0.2794)
			(end 0.12065 -0.2794)
			(stroke
				(width 0.1)
				(type default)
			)
			(layer "F.Fab")
		)
		(fp_line
			(start -0.12065 0.2794)
			(end -0.12065 0.3048)
			(stroke
				(width 0.1)
				(type default)
			)
			(layer "F.Fab")
		)
		(fp_line
			(start -0.12065 0.3048)
			(end -0.67945 0.3048)
			(stroke
				(width 0.1)
				(type default)
			)
			(layer "F.Fab")
		)
		(fp_line
			(start 0.120396 0.2794)
			(end -0.12065 0.2794)
			(stroke
				(width 0.1)
				(type default)
			)
			(layer "F.Fab")
		)
		(fp_line
			(start 0.120396 0.3048)
			(end 0.120396 0.2794)
			(stroke
				(width 0.1)
				(type default)
			)
			(layer "F.Fab")
		)
		(fp_line
			(start 0.12065 -0.3048)
			(end 0.67945 -0.3048)
			(stroke
				(width 0.1)
				(type default)
			)
			(layer "F.Fab")
		)
		(fp_line
			(start 0.12065 -0.2794)
			(end 0.12065 -0.3048)
			(stroke
				(width 0.1)
				(type default)
			)
			(layer "F.Fab")
		)
		(fp_line
			(start 0.67945 -0.3048)
			(end 0.67945 0.3048)
			(stroke
				(width 0.1)
				(type default)
			)
			(layer "F.Fab")
		)
		(fp_line
			(start 0.67945 0.3048)
			(end 0.120396 0.3048)
			(stroke
				(width 0.1)
				(type default)
			)
			(layer "F.Fab")
		)
		(pad "1" smd circle
			(at -0.40005 0)
			(size 0 0)
			(layers "F.Cu" "F.Mask" "F.Paste")
			(net "P12V_SSD6_OCP")
		)
		(pad "2" smd circle
			(at 0.40005 0)
			(size 0 0)
			(layers "F.Cu" "F.Mask" "F.Paste")
			(net "GND")
		)
	)
	(footprint ""
		(layer "F.Cu")
		(at 461.614012 -550.105834 180)
		(property "Reference" "SCREW_SSD13_1"
			(at -5.6007 -1.402334 0)
			(unlocked yes)
			(layer "B.SilkS")
			(effects
				(font
					(size 0.7874 0.5842)
					(thickness 0.1524)
				)
				(justify mirror)
			)
		)
		(property "Value" ""
			(at 0 0 180)
			(layer "F.Fab")
			(effects
				(font
					(size 1.27 1.27)
				)
			)
		)
		(duplicate_pad_numbers_are_jumpers no)
		(pad "1" thru_hole circle
			(at 0 0 180)
			(size 0.4572 0.4572)
			(drill 0.2032)
			(layers "*.Cu" "*.Mask")
			(remove_unused_layers no)
			(net "Net_9148")
			(clearance 0.127)
			(thermal_gap 0.127)
			(padstack
				(mode front_inner_back)
				(layer "Inner"
					(shape circle)
					(size 0.4572 0.4572)
					(clearance 0.127)
				)
				(layer "B.Cu"
					(shape circle)
					(size 0.508 0.508)
					(clearance 0.1016)
				)
			)
		)
	)
)
